# BASEBOARD_FAB2 (Tioga Pass) — schematic netlist excerpt (pin names and nets, part order shuffled) for the footprints in the layout excerpt that follows; sources: Cadence DE-HDL packaged netlist, KiCad conversion of Wiwynn_Tioga_Pass_MB.brd

R9L8  RES  2 1.0% CHIP  pkg 0402  page 100 : A = M_L_CPU_VREF ; B = M_L_VREF
R25W158  RES  1.00K 1% CHIP  pkg 0402  page 254 : A = P3V3_STBY ; B = PU_GTL2014_3_DIR
C5G22  CAP  47UF 4V 20% X6S  pkg 0805  page 242 : A = PVDDQ_ABC ; B = GND

(kicad_pcb
	(version 20260206)
	(generator "pcbnew")
	(generator_version "10.0")
	(general
		(thickness 1.6)
		(legacy_teardrops no)
	)
	(paper "A4")
	(title_block
		(title "Wiwynn_Tioga_Pass_MB.brd")
		(comment 1 "Tioga Pass / footprints 2882-2884 of 4770")
	)
	(layers
		(0 "F.Cu" signal "TOP")
		(4 "In1.Cu" signal "L2GND")
		(6 "In2.Cu" signal "L3")
		(8 "In3.Cu" signal "L4GND")
		(10 "In4.Cu" signal "L5")
		(12 "In5.Cu" signal "L6GND")
		(14 "In6.Cu" signal "L7VCC")
		(16 "In7.Cu" signal "L8VCC")
		(18 "In8.Cu" signal "L9GND")
		(20 "In9.Cu" signal "L10")
		(22 "In10.Cu" signal "L11GND")
		(24 "In11.Cu" signal "L12")
		(26 "In12.Cu" signal "L13GND")
		(2 "B.Cu" signal "BOTTOM")
		(9 "F.Adhes" user "F.Adhesive")
		(11 "B.Adhes" user "B.Adhesive")
		(13 "F.Paste" user "Package Geometry/Pastemask Top")
		(15 "B.Paste" user "Package Geometry/Pastemask Bottom")
		(5 "F.SilkS" user "Ref Des/Silkscreen Top")
		(7 "B.SilkS" user "Ref Des/Silkscreen Bottom")
		(1 "F.Mask" user "Board Geometry/Soldermask Top")
		(3 "B.Mask" user "Board Geometry/Soldermask Bottom")
		(17 "Dwgs.User" user "User.Drawings")
		(19 "Cmts.User" user "User.Comments")
		(21 "Eco1.User" user "User.Eco1")
		(23 "Eco2.User" user "User.Eco2")
		(25 "Edge.Cuts" user "Board Geometry/Outline")
		(27 "Margin" user)
		(31 "F.CrtYd" user "Package Geometry/Place Bound Top")
		(29 "B.CrtYd" user "Package Geometry/Place Bound Bottom")
		(35 "F.Fab" user "Ref Des/Assembly Top")
		(33 "B.Fab" user "Ref Des/Assembly Bottom")
	)
	(footprint ""
		(layer "B.Cu")
		(at 449.707 -141.097 90)
		(property "Reference" "R25W158"
			(at 0.8382 -0.67818 90)
			(unlocked yes)
			(layer "B.SilkS")
			(effects
				(font
					(size 0.4064 0.254)
					(thickness 0.1524)
				)
				(justify left mirror)
			)
		)
		(property "Value" ""
			(at 0 0 90)
			(layer "B.Fab")
			(effects
				(font
					(size 1.27 1.27)
				)
				(justify mirror)
			)
		)
		(duplicate_pad_numbers_are_jumpers no)
		(fp_poly
			(pts
				(xy 0.2794 -0.1016) (xy -0.2794 -0.1016) (xy -0.2794 0.9906) (xy 0.2794 0.9906)
			)
			(stroke
				(width 0)
				(type default)
			)
			(fill no)
			(layer "B.CrtYd")
		)
		(fp_line
			(start 0.2794 -0.1016)
			(end 0.2794 0.9906)
			(stroke
				(width 0.1)
				(type default)
			)
			(layer "B.Fab")
		)
		(fp_line
			(start -0.2794 -0.1016)
			(end 0.2794 -0.1016)
			(stroke
				(width 0.1)
				(type default)
			)
			(layer "B.Fab")
		)
		(fp_line
			(start 0.2794 0.9906)
			(end -0.2794 0.9906)
			(stroke
				(width 0.1)
				(type default)
			)
			(layer "B.Fab")
		)
		(fp_line
			(start -0.2794 0.9906)
			(end -0.2794 -0.1016)
			(stroke
				(width 0.1)
				(type default)
			)
			(layer "B.Fab")
		)
		(pad "1" smd rect
			(at 0 0 270)
			(size 0.508 0.508)
			(layers "B.Cu" "B.Mask" "B.Paste")
			(net "P3V3_STBY")
		)
		(pad "2" smd rect
			(at 0 0.889 270)
			(size 0.508 0.508)
			(layers "B.Cu" "B.Mask" "B.Paste")
			(net "PU_GTL2014_3_DIR")
		)
		(zone
			(layer "B.Cu")
			(hatch none 0.5)
			(connect_pads
				(clearance 0)
			)
			(min_thickness 0.25)
			(keepout
				(tracks allowed)
				(vias not_allowed)
				(pads allowed)
				(copperpour not_allowed)
				(footprints allowed)
			)
			(placement
				(enabled no)
				(sheetname "")
			)
			(fill
				(thermal_gap 0.5)
				(thermal_bridge_width 0.5)
				(island_removal_mode 0)
			)
			(polygon
				(pts
					(xy 449.961 -141.351) (xy 449.961 -140.843) (xy 450.342 -140.843) (xy 450.342 -141.351)
				)
			)
		)
		(zone
			(layer "B.Cu")
			(hatch none 0.5)
			(connect_pads
				(clearance 0)
			)
			(min_thickness 0.25)
			(keepout
				(tracks not_allowed)
				(vias allowed)
				(pads allowed)
				(copperpour not_allowed)
				(footprints allowed)
			)
			(placement
				(enabled no)
				(sheetname "")
			)
			(fill
				(thermal_gap 0.5)
				(thermal_bridge_width 0.5)
				(island_removal_mode 0)
			)
			(polygon
				(pts
					(xy 450.342 -141.351) (xy 450.342 -140.843) (xy 449.961 -140.843) (xy 449.961 -141.351)
				)
			)
		)
	)
	(footprint ""
		(layer "B.Cu")
		(at 27.658568 -144.4752 180)
		(property "Reference" "R9L8"
			(at 0 0 0)
			(layer "B.SilkS")
			(hide yes)
			(effects
				(font
					(size 1.27 1.27)
				)
				(justify mirror)
			)
		)
		(property "Value" ""
			(at 0 0 0)
			(layer "B.Fab")
			(effects
				(font
					(size 1.27 1.27)
				)
				(justify mirror)
			)
		)
		(duplicate_pad_numbers_are_jumpers no)
		(fp_poly
			(pts
				(xy 0.2794 -0.1016) (xy -0.2794 -0.1016) (xy -0.2794 0.9906) (xy 0.2794 0.9906)
			)
			(stroke
				(width 0)
				(type default)
			)
			(fill no)
			(layer "B.CrtYd")
		)
		(fp_line
			(start 0.2794 0.9906)
			(end -0.2794 0.9906)
			(stroke
				(width 0.1)
				(type default)
			)
			(layer "B.Fab")
		)
		(fp_line
			(start 0.2794 -0.1016)
			(end 0.2794 0.9906)
			(stroke
				(width 0.1)
				(type default)
			)
			(layer "B.Fab")
		)
		(fp_line
			(start -0.2794 0.9906)
			(end -0.2794 -0.1016)
			(stroke
				(width 0.1)
				(type default)
			)
			(layer "B.Fab")
		)
		(fp_line
			(start -0.2794 -0.1016)
			(end 0.2794 -0.1016)
			(stroke
				(width 0.1)
				(type default)
			)
			(layer "B.Fab")
		)
		(pad "1" smd rect
			(at 0 0)
			(size 0.508 0.508)
			(layers "B.Cu" "B.Mask" "B.Paste")
			(net "M_L_CPU_VREF")
		)
		(pad "2" smd rect
			(at 0 0.889)
			(size 0.508 0.508)
			(layers "B.Cu" "B.Mask" "B.Paste")
			(net "M_L_VREF")
		)
		(zone
			(layer "B.Cu")
			(hatch none 0.5)
			(connect_pads
				(clearance 0)
			)
			(min_thickness 0.25)
			(keepout
				(tracks not_allowed)
				(vias allowed)
				(pads allowed)
				(copperpour not_allowed)
				(footprints allowed)
			)
			(placement
				(enabled no)
				(sheetname "")
			)
			(fill
				(thermal_gap 0.5)
				(thermal_bridge_width 0.5)
				(island_removal_mode 0)
			)
			(polygon
				(pts
					(xy 27.404568 -145.1102) (xy 27.912568 -145.1102) (xy 27.912568 -144.7292) (xy 27.404568 -144.7292)
				)
			)
		)
		(zone
			(layer "B.Cu")
			(hatch none 0.5)
			(connect_pads
				(clearance 0)
			)
			(min_thickness 0.25)
			(keepout
				(tracks allowed)
				(vias not_allowed)
				(pads allowed)
				(copperpour not_allowed)
				(footprints allowed)
			)
			(placement
				(enabled no)
				(sheetname "")
			)
			(fill
				(thermal_gap 0.5)
				(thermal_bridge_width 0.5)
				(island_removal_mode 0)
			)
			(polygon
				(pts
					(xy 27.404568 -144.7292) (xy 27.912568 -144.7292) (xy 27.912568 -145.1102) (xy 27.404568 -145.1102)
				)
			)
		)
	)
	(footprint ""
		(layer "B.Cu")
		(at 259.4864 -13.0556 90)
		(property "Reference" "C5G22"
			(at -1.64973 0.78994 180)
			(unlocked yes)
			(layer "B.SilkS")
			(effects
				(font
					(size 0.7874 0.5842)
					(thickness 0.1524)
				)
				(justify mirror)
			)
		)
		(property "Value" ""
			(at 0 0 90)
			(layer "B.Fab")
			(effects
				(font
					(size 1.27 1.27)
				)
				(justify mirror)
			)
		)
		(duplicate_pad_numbers_are_jumpers no)
		(fp_rect
			(start -0.7239 -0.2159)
			(end 0.7239 1.9939)
			(stroke
				(width 0)
				(type default)
			)
			(fill no)
			(layer "B.CrtYd")
		)
		(fp_line
			(start 0.7239 -0.2159)
			(end 0.7239 1.9939)
			(stroke
				(width 0.1)
				(type default)
			)
			(layer "B.Fab")
		)
		(fp_line
			(start -0.7239 -0.2159)
			(end 0.7239 -0.2159)
			(stroke
				(width 0.1)
				(type default)
			)
			(layer "B.Fab")
		)
		(fp_line
			(start 0.7239 1.9939)
			(end -0.7239 1.9939)
			(stroke
				(width 0.1)
				(type default)
			)
			(layer "B.Fab")
		)
		(fp_line
			(start -0.7239 1.9939)
			(end -0.7239 -0.2159)
			(stroke
				(width 0.1)
				(type default)
			)
			(layer "B.Fab")
		)
		(pad "1" smd rect
			(at 0 0 270)
			(size 1.27 1.016)
			(layers "B.Cu" "B.Mask" "B.Paste")
			(net "PVDDQ_ABC")
		)
		(pad "2" smd rect
			(at 0 1.778 270)
			(size 1.27 1.016)
			(layers "B.Cu" "B.Mask" "B.Paste")
			(net "GND")
		)
		(zone
			(layer "B.Cu")
			(hatch none 0.5)
			(connect_pads
				(clearance 0)
			)
			(min_thickness 0.25)
			(keepout
				(tracks not_allowed)
				(vias allowed)
				(pads allowed)
				(copperpour not_allowed)
				(footprints allowed)
			)
			(placement
				(enabled no)
				(sheetname "")
			)
			(fill
				(thermal_gap 0.5)
				(thermal_bridge_width 0.5)
				(island_removal_mode 0)
			)
			(polygon
				(pts
					(xy 259.9944 -12.4206) (xy 260.7564 -12.4206) (xy 260.7564 -13.6906) (xy 259.9944 -13.6906)
				)
			)
		)
	)
)
